(kicad_pcb
	(version 20240108)
	(generator "pcbnew")
	(generator_version "8.0")
	(general
		(thickness 1.62)
		(legacy_teardrops no)
	)
	(paper "A4")
	(title_block
		(title "Jetson Orin Baseboard")
		(date "2025-03-12")
		(rev "1.3.4")
		(company "Antmicro Ltd")
		(comment 1 "www.antmicro.com")
		(comment 9 "footprints 536-537 of 677")
	)
	(layers
		(0 "F.Cu" signal)
		(1 "In1.Cu" signal)
		(2 "In2.Cu" signal)
		(3 "In3.Cu" signal)
		(4 "In4.Cu" jumper)
		(5 "In5.Cu" signal)
		(6 "In6.Cu" signal)
		(31 "B.Cu" signal)
		(32 "B.Adhes" user "B.Adhesive")
		(33 "F.Adhes" user "F.Adhesive")
		(34 "B.Paste" user)
		(35 "F.Paste" user)
		(36 "B.SilkS" user "B.Silkscreen")
		(37 "F.SilkS" user "F.Silkscreen")
		(38 "B.Mask" user)
		(39 "F.Mask" user)
		(40 "Dwgs.User" user "User.Drawings")
		(41 "Cmts.User" user "User.Comments")
		(42 "Eco1.User" user "User.Eco1")
		(43 "Eco2.User" user "User.Eco2")
		(44 "Edge.Cuts" user)
		(45 "Margin" user)
		(46 "B.CrtYd" user "B.Courtyard")
		(47 "F.CrtYd" user "F.Courtyard")
		(48 "B.Fab" user)
		(49 "F.Fab" user)
	)
	(footprint "antmicro-footprints:Conn_FFC_WE_68715014x22"
		(locked yes)
		(layer "B.Cu")
		(at 88.74 71.44)
		(property "Reference" "J8"
			(at -0.16 3.92 180)
			(layer "B.SilkS")
			(effects
				(font
					(size 0.7 0.7)
					(thickness 0.15)
				)
				(justify left bottom mirror)
			)
		)
		(property "Value" "Conn_FFC_WE_68715014522"
			(at 0 -4.499 180)
			(layer "B.Fab")
			(effects
				(font
					(size 0.7 0.7)
					(thickness 0.15)
				)
				(justify left bottom mirror)
			)
		)
		(property "Footprint" "antmicro-footprints:Conn_FFC_WE_68715014x22"
			(at 0 0 0)
			(layer "F.Fab")
			(hide yes)
			(effects
				(font
					(size 1.27 1.27)
					(thickness 0.15)
				)
			)
		)
		(property "Datasheet" "https://www.we-online.com/components/products/datasheet/68715014522.pdf"
			(at 0 0 0)
			(layer "F.Fab")
			(hide yes)
			(effects
				(font
					(size 1.27 1.27)
					(thickness 0.15)
				)
			)
		)
		(property "Author" "Antmicro"
			(at 0 0 0)
			(layer "B.Fab")
			(hide yes)
			(effects
				(font
					(size 1 1)
					(thickness 0.15)
				)
				(justify mirror)
			)
		)
		(property "License" "Apache-2.0"
			(at 0 0 0)
			(layer "B.Fab")
			(hide yes)
			(effects
				(font
					(size 1 1)
					(thickness 0.15)
				)
				(justify mirror)
			)
		)
		(property "MPN" "68715014522"
			(at 0 0 0)
			(layer "B.Fab")
			(hide yes)
			(effects
				(font
					(size 1 1)
					(thickness 0.15)
				)
				(justify mirror)
			)
		)
		(property "Manufacturer" "Würth Elektronik"
			(at 0 0 0)
			(layer "B.Fab")
			(hide yes)
			(effects
				(font
					(size 1 1)
					(thickness 0.15)
				)
				(justify mirror)
			)
		)
		(sheetname "CSI")
		(sheetfile "csi.kicad_sch")
		(attr smd)
		(fp_line
			(start -15.85 -2.7)
			(end 15.85 -2.7)
			(stroke
				(width 0.15)
				(type solid)
			)
			(layer "B.SilkS")
		)
		(fp_line
			(start -15.85 2.15)
			(end -15.85 -2.7)
			(stroke
				(width 0.15)
				(type solid)
			)
			(layer "B.SilkS")
		)
		(fp_line
			(start -12.5 2.15)
			(end -15.85 2.15)
			(stroke
				(width 0.15)
				(type solid)
			)
			(layer "B.SilkS")
		)
		(fp_line
			(start -12.5 2.976)
			(end -12.5 2.15)
			(stroke
				(width 0.15)
				(type solid)
			)
			(layer "B.SilkS")
		)
		(fp_line
			(start 12.499 2.15)
			(end 15.85 2.15)
			(stroke
				(width 0.15)
				(type solid)
			)
			(layer "B.SilkS")
		)
		(fp_line
			(start 12.499 2.976)
			(end -12.5 2.976)
			(stroke
				(width 0.15)
				(type solid)
			)
			(layer "B.SilkS")
		)
		(fp_line
			(start 12.499 2.976)
			(end 12.499 2.15)
			(stroke
				(width 0.15)
				(type solid)
			)
			(layer "B.SilkS")
		)
		(fp_line
			(start 15.85 2.15)
			(end 15.85 -2.7)
			(stroke
				(width 0.15)
				(type solid)
			)
			(layer "B.SilkS")
		)
		(fp_circle
			(center -12.9 2.9)
			(end -12.85 2.85)
			(stroke
				(width 0.15)
				(type solid)
			)
			(fill solid)
			(layer "B.SilkS")
		)
		(fp_rect
			(start -16.2 3.25)
			(end 16.2 -3.55)
			(stroke
				(width 0.05)
				(type solid)
			)
			(fill none)
			(layer "B.CrtYd")
		)
		(fp_text user "${REFERENCE}"
			(at -16.2 -8.9 180)
			(layer "B.Fab")
			(hide yes)
			(effects
				(font
					(size 0.7 0.7)
					(thickness 0.15)
				)
				(justify left bottom mirror)
			)
		)
		(fp_text user "License: Apache-2.0"
			(at -16.2 -7.7 180)
			(layer "B.Fab")
			(hide yes)
			(effects
				(font
					(size 0.7 0.7)
					(thickness 0.15)
				)
				(justify left bottom mirror)
			)
		)
		(fp_text user "Author: Antmicro"
			(at -16.2 -6.499 180)
			(layer "B.Fab")
			(hide yes)
			(effects
				(font
					(size 0.7 0.7)
					(thickness 0.15)
				)
				(justify left bottom mirror)
			)
		)
		(pad "1" smd roundrect
			(at -12.25 2.15)
			(size 0.3 1.2)
			(layers "B.Cu" "B.Paste" "B.Mask")
			(roundrect_rratio 0.25)
			(net 381 "unconnected-(J8-Pad1)")
			(pintype "passive+no_connect")
		)
		(pad "2" smd roundrect
			(at -11.75 2.15)
			(size 0.3 1.2)
			(layers "B.Cu" "B.Paste" "B.Mask")
			(roundrect_rratio 0.25)
			(net 382 "unconnected-(J8-Pad2)")
			(pintype "passive+no_connect")
		)
		(pad "3" smd roundrect
			(at -11.25 2.15)
			(size 0.3 1.2)
			(layers "B.Cu" "B.Paste" "B.Mask")
			(roundrect_rratio 0.25)
			(net 383 "unconnected-(J8-Pad3)")
			(pintype "passive+no_connect")
		)
		(pad "4" smd roundrect
			(at -10.75 2.15)
			(size 0.3 1.2)
			(layers "B.Cu" "B.Paste" "B.Mask")
			(roundrect_rratio 0.25)
			(net 384 "unconnected-(J8-Pad4)")
			(pintype "passive+no_connect")
		)
		(pad "5" smd roundrect
			(at -10.25 2.15)
			(size 0.3 1.2)
			(layers "B.Cu" "B.Paste" "B.Mask")
			(roundrect_rratio 0.25)
			(net 236 "/CSI/CSI1_1_D1_N")
			(pintype "passive")
		)
		(pad "6" smd roundrect
			(at -9.75 2.15)
			(size 0.3 1.2)
			(layers "B.Cu" "B.Paste" "B.Mask")
			(roundrect_rratio 0.25)
			(net 237 "/CSI/CSI1_1_D1_P")
			(pintype "passive")
		)
		(pad "7" smd roundrect
			(at -9.25 2.15)
			(size 0.3 1.2)
			(layers "B.Cu" "B.Paste" "B.Mask")
			(roundrect_rratio 0.25)
			(net 234 "/CSI/CSI1_1_D0_N")
			(pintype "passive")
		)
		(pad "8" smd roundrect
			(at -8.75 2.15)
			(size 0.3 1.2)
			(layers "B.Cu" "B.Paste" "B.Mask")
			(roundrect_rratio 0.25)
			(net 235 "/CSI/CSI1_1_D0_P")
			(pintype "passive")
		)
		(pad "9" smd roundrect
			(at -8.25 2.15)
			(size 0.3 1.2)
			(layers "B.Cu" "B.Paste" "B.Mask")
			(roundrect_rratio 0.25)
			(net 1 "GND")
			(pintype "passive")
		)
		(pad "10" smd roundrect
			(at -7.75 2.15)
			(size 0.3 1.2)
			(layers "B.Cu" "B.Paste" "B.Mask")
			(roundrect_rratio 0.25)
			(net 6 "CSI1_CLK_N")
			(pintype "passive")
		)
		(pad "11" smd roundrect
			(at -7.25 2.15)
			(size 0.3 1.2)
			(layers "B.Cu" "B.Paste" "B.Mask")
			(roundrect_rratio 0.25)
			(net 8 "CSI1_CLK_P")
			(pintype "passive")
		)
		(pad "12" smd roundrect
			(at -6.75 2.15)
			(size 0.3 1.2)
			(layers "B.Cu" "B.Paste" "B.Mask")
			(roundrect_rratio 0.25)
			(net 1 "GND")
			(pintype "passive")
		)
		(pad "13" smd roundrect
			(at -6.25 2.15)
			(size 0.3 1.2)
			(layers "B.Cu" "B.Paste" "B.Mask")
			(roundrect_rratio 0.25)
			(net 385 "unconnected-(J8-Pad13)")
			(pintype "passive+no_connect")
		)
		(pad "14" smd roundrect
			(at -5.75 2.15)
			(size 0.3 1.2)
			(layers "B.Cu" "B.Paste" "B.Mask")
			(roundrect_rratio 0.25)
			(net 386 "unconnected-(J8-Pad14)")
			(pintype "passive+no_connect")
		)
		(pad "15" smd roundrect
			(at -5.25 2.15)
			(size 0.3 1.2)
			(layers "B.Cu" "B.Paste" "B.Mask")
			(roundrect_rratio 0.25)
			(net 1 "GND")
			(pintype "passive")
		)
		(pad "16" smd roundrect
			(at -4.75 2.15)
			(size 0.3 1.2)
			(layers "B.Cu" "B.Paste" "B.Mask")
			(roundrect_rratio 0.25)
			(net 387 "unconnected-(J8-Pad16)")
			(pintype "passive+no_connect")
		)
		(pad "17" smd roundrect
			(at -4.25 2.15)
			(size 0.3 1.2)
			(layers "B.Cu" "B.Paste" "B.Mask")
			(roundrect_rratio 0.25)
			(net 388 "unconnected-(J8-Pad17)")
			(pintype "passive+no_connect")
		)
		(pad "18" smd roundrect
			(at -3.75 2.15)
			(size 0.3 1.2)
			(layers "B.Cu" "B.Paste" "B.Mask")
			(roundrect_rratio 0.25)
			(net 1 "GND")
			(pintype "passive")
		)
		(pad "19" smd roundrect
			(at -3.25 2.15)
			(size 0.3 1.2)
			(layers "B.Cu" "B.Paste" "B.Mask")
			(roundrect_rratio 0.25)
			(net 389 "unconnected-(J8-Pad19)")
			(pintype "passive+no_connect")
		)
		(pad "20" smd roundrect
			(at -2.75 2.15)
			(size 0.3 1.2)
			(layers "B.Cu" "B.Paste" "B.Mask")
			(roundrect_rratio 0.25)
			(net 392 "unconnected-(J8-Pad20)")
			(pintype "passive+no_connect")
		)
		(pad "21" smd roundrect
			(at -2.25 2.15)
			(size 0.3 1.2)
			(layers "B.Cu" "B.Paste" "B.Mask")
			(roundrect_rratio 0.25)
			(net 399 "unconnected-(J8-Pad21)")
			(pintype "passive+no_connect")
		)
		(pad "22" smd roundrect
			(at -1.75 2.15)
			(size 0.3 1.2)
			(layers "B.Cu" "B.Paste" "B.Mask")
			(roundrect_rratio 0.25)
			(net 400 "unconnected-(J8-Pad22)")
			(pintype "passive+no_connect")
		)
		(pad "23" smd roundrect
			(at -1.25 2.15)
			(size 0.3 1.2)
			(layers "B.Cu" "B.Paste" "B.Mask")
			(roundrect_rratio 0.25)
			(net 238 "/CSI/CSI3_1_D1_N")
			(pintype "passive")
		)
		(pad "24" smd roundrect
			(at -0.75 2.15)
			(size 0.3 1.2)
			(layers "B.Cu" "B.Paste" "B.Mask")
			(roundrect_rratio 0.25)
			(net 239 "/CSI/CSI3_1_D1_P")
			(pintype "passive")
		)
		(pad "25" smd roundrect
			(at -0.25 2.15)
			(size 0.3 1.2)
			(layers "B.Cu" "B.Paste" "B.Mask")
			(roundrect_rratio 0.25)
			(net 240 "/CSI/CSI3_1_D0_N")
			(pintype "passive")
		)
		(pad "26" smd roundrect
			(at 0.248 2.15)
			(size 0.3 1.2)
			(layers "B.Cu" "B.Paste" "B.Mask")
			(roundrect_rratio 0.25)
			(net 241 "/CSI/CSI3_1_D0_P")
			(pintype "passive")
		)
		(pad "27" smd roundrect
			(at 0.748 2.15)
			(size 0.3 1.2)
			(layers "B.Cu" "B.Paste" "B.Mask")
			(roundrect_rratio 0.25)
			(net 1 "GND")
			(pintype "passive")
		)
		(pad "28" smd roundrect
			(at 1.249 2.15)
			(size 0.3 1.2)
			(layers "B.Cu" "B.Paste" "B.Mask")
			(roundrect_rratio 0.25)
			(net 18 "CSI3_CLK_N")
			(pintype "passive")
		)
		(pad "29" smd roundrect
			(at 1.749 2.15)
			(size 0.3 1.2)
			(layers "B.Cu" "B.Paste" "B.Mask")
			(roundrect_rratio 0.25)
			(net 20 "CSI3_CLK_P")
			(pintype "passive")
		)
		(pad "30" smd roundrect
			(at 2.249 2.15)
			(size 0.3 1.2)
			(layers "B.Cu" "B.Paste" "B.Mask")
			(roundrect_rratio 0.25)
			(net 1 "GND")
			(pintype "passive")
		)
		(pad "31" smd roundrect
			(at 2.749 2.15)
			(size 0.3 1.2)
			(layers "B.Cu" "B.Paste" "B.Mask")
			(roundrect_rratio 0.25)
			(net 401 "unconnected-(J8-Pad31)")
			(pintype "passive+no_connect")
		)
		(pad "32" smd roundrect
			(at 3.249 2.15)
			(size 0.3 1.2)
			(layers "B.Cu" "B.Paste" "B.Mask")
			(roundrect_rratio 0.25)
			(net 406 "/CSI/VSYNC_CAM2_3V3")
			(pintype "passive")
		)
		(pad "33" smd roundrect
			(at 3.749 2.15)
			(size 0.3 1.2)
			(layers "B.Cu" "B.Paste" "B.Mask")
			(roundrect_rratio 0.25)
			(net 405 "unconnected-(J8-Pad33)")
			(pintype "passive+no_connect")
		)
		(pad "34" smd roundrect
			(at 4.248 2.15)
			(size 0.3 1.2)
			(layers "B.Cu" "B.Paste" "B.Mask")
			(roundrect_rratio 0.25)
			(net 402 "/CSI/VSYNC_CAM3_3V3")
			(pintype "passive")
		)
		(pad "35" smd roundrect
			(at 4.748 2.15)
			(size 0.3 1.2)
			(layers "B.Cu" "B.Paste" "B.Mask")
			(roundrect_rratio 0.25)
			(net 407 "unconnected-(J8-Pad35)")
			(pintype "passive+no_connect")
		)
		(pad "36" smd roundrect
			(at 5.248 2.15)
			(size 0.3 1.2)
			(layers "B.Cu" "B.Paste" "B.Mask")
			(roundrect_rratio 0.25)
			(net 408 "unconnected-(J8-Pad36)")
			(pintype "passive+no_connect")
		)
		(pad "37" smd roundrect
			(at 5.749 2.15)
			(size 0.3 1.2)
			(layers "B.Cu" "B.Paste" "B.Mask")
			(roundrect_rratio 0.25)
			(net 409 "unconnected-(J8-Pad37)")
			(pintype "passive+no_connect")
		)
		(pad "38" smd roundrect
			(at 6.249 2.15)
			(size 0.3 1.2)
			(layers "B.Cu" "B.Paste" "B.Mask")
			(roundrect_rratio 0.25)
			(net 410 "unconnected-(J8-Pad38)")
			(pintype "passive+no_connect")
		)
		(pad "39" smd roundrect
			(at 6.749 2.15)
			(size 0.3 1.2)
			(layers "B.Cu" "B.Paste" "B.Mask")
			(roundrect_rratio 0.25)
			(net 575 "Net-(R51-R1.2)")
			(pintype "passive")
		)
		(pad "40" smd roundrect
			(at 7.249 2.15)
			(size 0.3 1.2)
			(layers "B.Cu" "B.Paste" "B.Mask")
			(roundrect_rratio 0.25)
			(net 577 "Net-(R51-R2.2)")
			(pintype "passive")
		)
		(pad "41" smd roundrect
			(at 7.749 2.15)
			(size 0.3 1.2)
			(layers "B.Cu" "B.Paste" "B.Mask")
			(roundrect_rratio 0.25)
			(net 602 "Net-(R51-R3.2)")
			(pintype "passive")
		)
		(pad "42" smd roundrect
			(at 8.249 2.15)
			(size 0.3 1.2)
			(layers "B.Cu" "B.Paste" "B.Mask")
			(roundrect_rratio 0.25)
			(net 603 "Net-(R51-R4.2)")
			(pintype "passive")
		)
		(pad "43" smd roundrect
			(at 8.749 2.15)
			(size 0.3 1.2)
			(layers "B.Cu" "B.Paste" "B.Mask")
			(roundrect_rratio 0.25)
			(net 421 "unconnected-(J8-Pad43)")
			(pintype "passive+no_connect")
		)
		(pad "44" smd roundrect
			(at 9.249 2.15)
			(size 0.3 1.2)
			(layers "B.Cu" "B.Paste" "B.Mask")
			(roundrect_rratio 0.25)
			(net 423 "unconnected-(J8-Pad44)")
			(pintype "passive+no_connect")
		)
		(pad "45" smd roundrect
			(at 9.749 2.15)
			(size 0.3 1.2)
			(layers "B.Cu" "B.Paste" "B.Mask")
			(roundrect_rratio 0.25)
			(net 425 "unconnected-(J8-Pad45)")
			(pintype "passive+no_connect")
		)
		(pad "46" smd roundrect
			(at 10.249 2.15)
			(size 0.3 1.2)
			(layers "B.Cu" "B.Paste" "B.Mask")
			(roundrect_rratio 0.25)
			(net 426 "unconnected-(J8-Pad46)")
			(pintype "passive+no_connect")
		)
		(pad "47" smd roundrect
			(at 10.749 2.15)
			(size 0.3 1.2)
			(layers "B.Cu" "B.Paste" "B.Mask")
			(roundrect_rratio 0.25)
			(net 110 "/CSI/CSIB_3V3")
			(pintype "passive")
		)
		(pad "48" smd roundrect
			(at 11.249 2.15)
			(size 0.3 1.2)
			(layers "B.Cu" "B.Paste" "B.Mask")
			(roundrect_rratio 0.25)
			(net 110 "/CSI/CSIB_3V3")
			(pintype "passive")
		)
		(pad "49" smd roundrect
			(at 11.749 2.15)
			(size 0.3 1.2)
			(layers "B.Cu" "B.Paste" "B.Mask")
			(roundrect_rratio 0.25)
			(net 111 "/CSI/CSIB_5V")
			(pintype "passive")
		)
		(pad "50" smd roundrect
			(at 12.249 2.15)
			(size 0.3 1.2)
			(layers "B.Cu" "B.Paste" "B.Mask")
			(roundrect_rratio 0.25)
			(net 111 "/CSI/CSIB_5V")
			(pintype "passive")
		)
		(pad "MP1" smd roundrect
			(at -14.198 0.3)
			(size 2.7 3)
			(layers "B.Cu" "B.Paste" "B.Mask")
			(roundrect_rratio 0.05)
			(net 1 "GND")
			(pinfunction "MP")
			(pintype "passive")
		)
		(pad "MP2" smd roundrect
			(at 14.198 0.3)
			(size 2.7 3)
			(layers "B.Cu" "B.Paste" "B.Mask")
			(roundrect_rratio 0.05)
			(net 1 "GND")
			(pinfunction "MP")
			(pintype "passive")
		)
	)
	(footprint "antmicro-footprints:R_0603_1608Metric"
		(layer "B.Cu")
		(at 71.6 111.4 180)
		(descr "Resistor SMD 0603")
		(tags "resistor SMD 0603")
		(property "Reference" "R253"
			(at -0.67 -1.425 0)
			(layer "B.SilkS")
			(effects
				(font
					(size 0.7 0.7)
					(thickness 0.15)
				)
				(justify left bottom mirror)
			)
		)
		(property "Value" "R_0R_22.4A_0603"
			(at 0 -1.6 0)
			(layer "B.Fab")
			(effects
				(font
					(size 0.7 0.7)
					(thickness 0.15)
				)
				(justify left bottom mirror)
			)
		)
		(property "Footprint" "antmicro-footprints:R_0603_1608Metric"
			(at 0 0 180)
			(layer "F.Fab")
			(hide yes)
			(effects
				(font
					(size 1.27 1.27)
					(thickness 0.15)
				)
			)
		)
		(property "Datasheet" "https://fscdn.rohm.com/en/products/databook/datasheet/passive/resistor/chip_resistor/pmr-jpw-e.pdf"
			(at 0 0 180)
			(layer "F.Fab")
			(hide yes)
			(effects
				(font
					(size 1.27 1.27)
					(thickness 0.15)
				)
			)
		)
		(property "Author" "Antmicro"
			(at 143.2 222.8 0)
			(layer "B.Fab")
			(hide yes)
			(effects
				(font
					(size 1 1)
					(thickness 0.15)
				)
				(justify mirror)
			)
		)
		(property "License" "Apache-2.0"
			(at 143.2 222.8 0)
			(layer "B.Fab")
			(hide yes)
			(effects
				(font
					(size 1 1)
					(thickness 0.15)
				)
				(justify mirror)
			)
		)
		(property "MPN" "PMR03EZPJ000"
			(at 143.2 222.8 0)
			(layer "B.Fab")
			(hide yes)
			(effects
				(font
					(size 1 1)
					(thickness 0.15)
				)
				(justify mirror)
			)
		)
		(property "Manufacturer" "ROHM Semiconductor"
			(at 143.2 222.8 0)
			(layer "B.Fab")
			(hide yes)
			(effects
				(font
					(size 1 1)
					(thickness 0.15)
				)
				(justify mirror)
			)
		)
		(property "Max. Curr." "22.4A"
			(at 143.2 222.8 0)
			(layer "B.Fab")
			(hide yes)
			(effects
				(font
					(size 1 1)
					(thickness 0.15)
				)
				(justify mirror)
			)
		)
		(property "Tolerance" "template_tolerance"
			(at 143.2 222.8 0)
			(layer "B.Fab")
			(hide yes)
			(effects
				(font
					(size 1 1)
					(thickness 0.15)
				)
				(justify mirror)
			)
		)
		(property "Val" "0R"
			(at 143.2 222.8 0)
			(layer "B.Fab")
			(hide yes)
			(effects
				(font
					(size 1 1)
					(thickness 0.15)
				)
				(justify mirror)
			)
		)
		(sheetname "Supply")
		(sheetfile "supply.kicad_sch")
		(attr smd)
		(fp_line
			(start 0.15 0.4)
			(end -0.15 0.4)
			(stroke
				(width 0.15)
				(type solid)
			)
			(layer "B.SilkS")
		)
		(fp_line
			(start 0.15 -0.4)
			(end -0.15 -0.4)
			(stroke
				(width 0.15)
				(type solid)
			)
			(layer "B.SilkS")
		)
		(fp_rect
			(start -1.25 0.65)
			(end 1.25 -0.65)
			(stroke
				(width 0.05)
				(type solid)
			)
			(fill none)
			(layer "B.CrtYd")
		)
		(fp_rect
			(start -0.8 0.4)
			(end 0.8 -0.4)
			(stroke
				(width 0.15)
				(type solid)
			)
			(fill none)
			(layer "B.Fab")
		)
		(fp_text user "License: Apache-2.0"
			(at -1.25 -5.9 0)
			(layer "B.Fab")
			(hide yes)
			(effects
				(font
					(size 0.7 0.7)
					(thickness 0.15)
				)
				(justify left bottom mirror)
			)
		)
		(fp_text user "${REFERENCE}"
			(at -1.25 -3.898 0)
			(layer "B.Fab")
			(hide yes)
			(effects
				(font
					(size 0.7 0.7)
					(thickness 0.15)
				)
				(justify left bottom mirror)
			)
		)
		(fp_text user "Author: Antmicro"
			(at -1.25 -4.9 0)
			(layer "B.Fab")
			(hide yes)
			(effects
				(font
					(size 0.7 0.7)
					(thickness 0.15)
				)
				(justify left bottom mirror)
			)
		)
		(pad "1" smd roundrect
			(at -0.7 0 180)
			(size 0.8 1)
			(layers "B.Cu" "B.Paste" "B.Mask")
			(roundrect_rratio 0.2)
			(net 481 "USBPD2_HV")
			(pintype "passive")
		)
		(pad "2" smd roundrect
			(at 0.7 0 180)
			(size 0.8 1)
			(layers "B.Cu" "B.Paste" "B.Mask")
			(roundrect_rratio 0.2)
			(net 328 "/Supply/VCC_IN")
			(pintype "passive")
		)
	)
)
